(kicad_pcb
	(version 20260206)
	(generator "pcbnew")
	(generator_version "10.0")
	(general
		(thickness 1.6)
		(legacy_teardrops no)
	)
	(paper "A4")
	(title_block
		(title "03242023_DA0F0TMBIJ0_F0T_Motherboard_J_brd_V01_OCP.brd")
		(comment 1 "Grand Teton / footprint 2874 of 6105 (J29), pads 1-112 of 291")
	)
	(layers
		(0 "F.Cu" signal "TOP")
		(4 "In1.Cu" signal "GND")
		(6 "In2.Cu" signal "IN1")
		(8 "In3.Cu" signal "GND1")
		(10 "In4.Cu" signal "IN2")
		(12 "In5.Cu" signal "GND2")
		(14 "In6.Cu" signal "IN3")
		(16 "In7.Cu" signal "GND3")
		(18 "In8.Cu" signal "VCC")
		(20 "In9.Cu" signal "VCC1")
		(22 "In10.Cu" signal "GND4")
		(24 "In11.Cu" signal "IN4")
		(26 "In12.Cu" signal "GND5")
		(28 "In13.Cu" signal "IN5")
		(30 "In14.Cu" signal "GND6")
		(32 "In15.Cu" signal "IN6")
		(34 "In16.Cu" signal "GND7")
		(2 "B.Cu" signal "BOTTOM")
		(9 "F.Adhes" user "F.Adhesive")
		(11 "B.Adhes" user "B.Adhesive")
		(13 "F.Paste" user "Package Geometry/Pastemask Top")
		(15 "B.Paste" user "Package Geometry/Pastemask Bottom")
		(5 "F.SilkS" user "Ref Des/Silkscreen Top")
		(7 "B.SilkS" user "Ref Des/Silkscreen Bottom")
		(1 "F.Mask" user "Board Geometry/Soldermask Top")
		(3 "B.Mask" user "Board Geometry/Soldermask Bottom")
		(17 "Dwgs.User" user "User.Drawings")
		(19 "Cmts.User" user "User.Comments")
		(21 "Eco1.User" user "User.Eco1")
		(23 "Eco2.User" user "User.Eco2")
		(25 "Edge.Cuts" user "Board Geometry/Outline")
		(27 "Margin" user)
		(31 "F.CrtYd" user "Package Geometry/Place Bound Top")
		(29 "B.CrtYd" user "Package Geometry/Place Bound Bottom")
		(35 "F.Fab" user "Ref Des/Assembly Top")
		(33 "B.Fab" user "Ref Des/Assembly Bottom")
	)
	(footprint ""
		(layer "F.Cu")
		(at 198.58228 -258.091686)
		(property "Reference" "J29"
			(at -3.683 -81.702148 0)
			(unlocked yes)
			(layer "F.SilkS")
			(effects
				(font
					(size 0.7874 0.5842)
					(thickness 0.1524)
				)
				(justify left)
			)
		)
		(property "Value" ""
			(at 0 0 0)
			(layer "F.Fab")
			(effects
				(font
					(size 1.27 1.27)
				)
			)
		)
		(duplicate_pad_numbers_are_jumpers no)
		(pad "1" smd rect
			(at -2.050034 -63.324994 270)
			(size 0.519938 1.4986)
			(layers "F.Cu" "F.Mask" "F.Paste")
			(net "P12V_S3_AUX_CPU1_NVDIMM")
		)
		(pad "2" smd rect
			(at -2.050034 -62.47511 270)
			(size 0.519938 1.4986)
			(layers "F.Cu" "F.Mask" "F.Paste")
			(net "TP_CHG_CPU1_DIMM1_FRU_0")
		)
		(pad "3" smd rect
			(at -2.050034 -61.624972 270)
			(size 0.519938 1.4986)
			(layers "F.Cu" "F.Mask" "F.Paste")
			(net "P3V3_AUX")
		)
		(pad "4" smd rect
			(at -2.050034 -60.775088 270)
			(size 0.519938 1.4986)
			(layers "F.Cu" "F.Mask" "F.Paste")
			(net "I3C_SPD_DDREFGH_CPU1_LVC1_SCL_4")
		)
		(pad "5" smd rect
			(at -2.050034 -59.92495 270)
			(size 0.519938 1.4986)
			(layers "F.Cu" "F.Mask" "F.Paste")
			(net "I3C_SPD_DDREFGH_CPU1_LVC1_SDA")
		)
		(pad "6" smd rect
			(at -2.050034 -59.075066 270)
			(size 0.519938 1.4986)
			(layers "F.Cu" "F.Mask" "F.Paste")
			(net "GND")
		)
		(pad "7" smd rect
			(at -2.050034 -58.224928 270)
			(size 0.519938 1.4986)
			(layers "F.Cu" "F.Mask" "F.Paste")
			(net "M_G_CPU1_SA_DQ<0>")
		)
		(pad "8" smd rect
			(at -2.050034 -57.375044 270)
			(size 0.519938 1.4986)
			(layers "F.Cu" "F.Mask" "F.Paste")
			(net "GND")
		)
		(pad "9" smd rect
			(at -2.050034 -56.524906 270)
			(size 0.519938 1.4986)
			(layers "F.Cu" "F.Mask" "F.Paste")
			(net "M_G_CPU1_SA_DQ<1>")
		)
		(pad "10" smd rect
			(at -2.050034 -55.675022 270)
			(size 0.519938 1.4986)
			(layers "F.Cu" "F.Mask" "F.Paste")
			(net "GND")
		)
		(pad "11" smd rect
			(at -2.050034 -54.824884 270)
			(size 0.519938 1.4986)
			(layers "F.Cu" "F.Mask" "F.Paste")
			(net "M_G_CPU1_SA_DQS_DP<0>")
		)
		(pad "12" smd rect
			(at -2.050034 -53.975 270)
			(size 0.519938 1.4986)
			(layers "F.Cu" "F.Mask" "F.Paste")
			(net "M_G_CPU1_SA_DQS_DN<0>")
		)
		(pad "13" smd rect
			(at -2.050034 -53.125116 270)
			(size 0.519938 1.4986)
			(layers "F.Cu" "F.Mask" "F.Paste")
			(net "GND")
		)
		(pad "14" smd rect
			(at -2.050034 -52.274978 270)
			(size 0.519938 1.4986)
			(layers "F.Cu" "F.Mask" "F.Paste")
			(net "M_G_CPU1_SA_DQ<4>")
		)
		(pad "15" smd rect
			(at -2.050034 -51.425094 270)
			(size 0.519938 1.4986)
			(layers "F.Cu" "F.Mask" "F.Paste")
			(net "GND")
		)
		(pad "16" smd rect
			(at -2.050034 -50.574956 270)
			(size 0.519938 1.4986)
			(layers "F.Cu" "F.Mask" "F.Paste")
			(net "M_G_CPU1_SA_DQ<5>")
		)
		(pad "17" smd rect
			(at -2.050034 -49.725072 270)
			(size 0.519938 1.4986)
			(layers "F.Cu" "F.Mask" "F.Paste")
			(net "GND")
		)
		(pad "18" smd rect
			(at -2.050034 -48.874934 270)
			(size 0.519938 1.4986)
			(layers "F.Cu" "F.Mask" "F.Paste")
			(net "M_G_CPU1_SA_DQ<8>")
		)
		(pad "19" smd rect
			(at -2.050034 -48.02505 270)
			(size 0.519938 1.4986)
			(layers "F.Cu" "F.Mask" "F.Paste")
			(net "GND")
		)
		(pad "20" smd rect
			(at -2.050034 -47.174912 270)
			(size 0.519938 1.4986)
			(layers "F.Cu" "F.Mask" "F.Paste")
			(net "M_G_CPU1_SA_DQ<9>")
		)
		(pad "21" smd rect
			(at -2.050034 -46.325028 270)
			(size 0.519938 1.4986)
			(layers "F.Cu" "F.Mask" "F.Paste")
			(net "GND")
		)
		(pad "22" smd rect
			(at -2.050034 -45.47489 270)
			(size 0.519938 1.4986)
			(layers "F.Cu" "F.Mask" "F.Paste")
			(net "M_G_CPU1_SA_DQS_DP<1>")
		)
		(pad "23" smd rect
			(at -2.050034 -44.625006 270)
			(size 0.519938 1.4986)
			(layers "F.Cu" "F.Mask" "F.Paste")
			(net "M_G_CPU1_SA_DQS_DN<1>")
		)
		(pad "24" smd rect
			(at -2.050034 -43.775122 270)
			(size 0.519938 1.4986)
			(layers "F.Cu" "F.Mask" "F.Paste")
			(net "GND")
		)
		(pad "25" smd rect
			(at -2.050034 -42.924984 270)
			(size 0.519938 1.4986)
			(layers "F.Cu" "F.Mask" "F.Paste")
			(net "M_G_CPU1_SA_DQ<12>")
		)
		(pad "26" smd rect
			(at -2.050034 -42.0751 270)
			(size 0.519938 1.4986)
			(layers "F.Cu" "F.Mask" "F.Paste")
			(net "GND")
		)
		(pad "27" smd rect
			(at -2.050034 -41.224962 270)
			(size 0.519938 1.4986)
			(layers "F.Cu" "F.Mask" "F.Paste")
			(net "M_G_CPU1_SA_DQ<13>")
		)
		(pad "28" smd rect
			(at -2.050034 -40.375078 270)
			(size 0.519938 1.4986)
			(layers "F.Cu" "F.Mask" "F.Paste")
			(net "GND")
		)
		(pad "29" smd rect
			(at -2.050034 -39.52494 270)
			(size 0.519938 1.4986)
			(layers "F.Cu" "F.Mask" "F.Paste")
			(net "M_G_CPU1_SA_DQ<16>")
		)
		(pad "30" smd rect
			(at -2.050034 -38.675056 270)
			(size 0.519938 1.4986)
			(layers "F.Cu" "F.Mask" "F.Paste")
			(net "GND")
		)
		(pad "31" smd rect
			(at -2.050034 -37.824918 270)
			(size 0.519938 1.4986)
			(layers "F.Cu" "F.Mask" "F.Paste")
			(net "M_G_CPU1_SA_DQ<17>")
		)
		(pad "32" smd rect
			(at -2.050034 -36.975034 270)
			(size 0.519938 1.4986)
			(layers "F.Cu" "F.Mask" "F.Paste")
			(net "GND")
		)
		(pad "33" smd rect
			(at -2.050034 -36.124896 270)
			(size 0.519938 1.4986)
			(layers "F.Cu" "F.Mask" "F.Paste")
			(net "M_G_CPU1_SA_DQS_DP<2>")
		)
		(pad "34" smd rect
			(at -2.050034 -35.275012 270)
			(size 0.519938 1.4986)
			(layers "F.Cu" "F.Mask" "F.Paste")
			(net "M_G_CPU1_SA_DQS_DN<2>")
		)
		(pad "35" smd rect
			(at -2.050034 -34.425128 270)
			(size 0.519938 1.4986)
			(layers "F.Cu" "F.Mask" "F.Paste")
			(net "GND")
		)
		(pad "36" smd rect
			(at -2.050034 -33.57499 270)
			(size 0.519938 1.4986)
			(layers "F.Cu" "F.Mask" "F.Paste")
			(net "M_G_CPU1_SA_DQ<20>")
		)
		(pad "37" smd rect
			(at -2.050034 -32.725106 270)
			(size 0.519938 1.4986)
			(layers "F.Cu" "F.Mask" "F.Paste")
			(net "GND")
		)
		(pad "38" smd rect
			(at -2.050034 -31.874968 270)
			(size 0.519938 1.4986)
			(layers "F.Cu" "F.Mask" "F.Paste")
			(net "M_G_CPU1_SA_DQ<21>")
		)
		(pad "39" smd rect
			(at -2.050034 -31.025084 270)
			(size 0.519938 1.4986)
			(layers "F.Cu" "F.Mask" "F.Paste")
			(net "GND")
		)
		(pad "40" smd rect
			(at -2.050034 -30.174946 270)
			(size 0.519938 1.4986)
			(layers "F.Cu" "F.Mask" "F.Paste")
			(net "M_G_CPU1_SA_DQ<24>")
		)
		(pad "41" smd rect
			(at -2.050034 -29.325062 270)
			(size 0.519938 1.4986)
			(layers "F.Cu" "F.Mask" "F.Paste")
			(net "GND")
		)
		(pad "42" smd rect
			(at -2.050034 -28.474924 270)
			(size 0.519938 1.4986)
			(layers "F.Cu" "F.Mask" "F.Paste")
			(net "M_G_CPU1_SA_DQ<25>")
		)
		(pad "43" smd rect
			(at -2.050034 -27.62504 270)
			(size 0.519938 1.4986)
			(layers "F.Cu" "F.Mask" "F.Paste")
			(net "GND")
		)
		(pad "44" smd rect
			(at -2.050034 -26.774902 270)
			(size 0.519938 1.4986)
			(layers "F.Cu" "F.Mask" "F.Paste")
			(net "M_G_CPU1_SA_DQS_DP<3>")
		)
		(pad "45" smd rect
			(at -2.050034 -25.925018 270)
			(size 0.519938 1.4986)
			(layers "F.Cu" "F.Mask" "F.Paste")
			(net "M_G_CPU1_SA_DQS_DN<3>")
		)
		(pad "46" smd rect
			(at -2.050034 -25.07488 270)
			(size 0.519938 1.4986)
			(layers "F.Cu" "F.Mask" "F.Paste")
			(net "GND")
		)
		(pad "47" smd rect
			(at -2.050034 -24.224996 270)
			(size 0.519938 1.4986)
			(layers "F.Cu" "F.Mask" "F.Paste")
			(net "M_G_CPU1_SA_DQ<28>")
		)
		(pad "48" smd rect
			(at -2.050034 -23.375112 270)
			(size 0.519938 1.4986)
			(layers "F.Cu" "F.Mask" "F.Paste")
			(net "GND")
		)
		(pad "49" smd rect
			(at -2.050034 -22.524974 270)
			(size 0.519938 1.4986)
			(layers "F.Cu" "F.Mask" "F.Paste")
			(net "M_G_CPU1_SA_DQ<29>")
		)
		(pad "50" smd rect
			(at -2.050034 -21.67509 270)
			(size 0.519938 1.4986)
			(layers "F.Cu" "F.Mask" "F.Paste")
			(net "GND")
		)
		(pad "51" smd rect
			(at -2.050034 -20.824952 270)
			(size 0.519938 1.4986)
			(layers "F.Cu" "F.Mask" "F.Paste")
			(net "M_G_CPU1_SA_CB<0>")
		)
		(pad "52" smd rect
			(at -2.050034 -19.975068 270)
			(size 0.519938 1.4986)
			(layers "F.Cu" "F.Mask" "F.Paste")
			(net "GND")
		)
		(pad "53" smd rect
			(at -2.050034 -19.12493 270)
			(size 0.519938 1.4986)
			(layers "F.Cu" "F.Mask" "F.Paste")
			(net "M_G_CPU1_SA_CB<1>")
		)
		(pad "54" smd rect
			(at -2.050034 -18.275046 270)
			(size 0.519938 1.4986)
			(layers "F.Cu" "F.Mask" "F.Paste")
			(net "GND")
		)
		(pad "55" smd rect
			(at -2.050034 -17.424908 270)
			(size 0.519938 1.4986)
			(layers "F.Cu" "F.Mask" "F.Paste")
			(net "M_G_CPU1_SA_DQS_DP<4>")
		)
		(pad "56" smd rect
			(at -2.050034 -16.575024 270)
			(size 0.519938 1.4986)
			(layers "F.Cu" "F.Mask" "F.Paste")
			(net "M_G_CPU1_SA_DQS_DN<4>")
		)
		(pad "57" smd rect
			(at -2.050034 -15.724886 270)
			(size 0.519938 1.4986)
			(layers "F.Cu" "F.Mask" "F.Paste")
			(net "GND")
		)
		(pad "58" smd rect
			(at -2.050034 -14.875002 270)
			(size 0.519938 1.4986)
			(layers "F.Cu" "F.Mask" "F.Paste")
			(net "M_G_CPU1_SA_CB<4>")
		)
		(pad "59" smd rect
			(at -2.050034 -14.025118 270)
			(size 0.519938 1.4986)
			(layers "F.Cu" "F.Mask" "F.Paste")
			(net "GND")
		)
		(pad "60" smd rect
			(at -2.050034 -13.17498 270)
			(size 0.519938 1.4986)
			(layers "F.Cu" "F.Mask" "F.Paste")
			(net "M_G_CPU1_SA_CB<5>")
		)
		(pad "61" smd rect
			(at -2.050034 -12.325096 270)
			(size 0.519938 1.4986)
			(layers "F.Cu" "F.Mask" "F.Paste")
			(net "GND")
		)
		(pad "62" smd rect
			(at -2.050034 -11.474958 270)
			(size 0.519938 1.4986)
			(layers "F.Cu" "F.Mask" "F.Paste")
			(net "M_G_CPU1_ALERT_N")
		)
		(pad "63" smd rect
			(at -2.050034 -10.625074 270)
			(size 0.519938 1.4986)
			(layers "F.Cu" "F.Mask" "F.Paste")
			(net "GND")
		)
		(pad "64" smd rect
			(at -2.050034 -9.774936 270)
			(size 0.519938 1.4986)
			(layers "F.Cu" "F.Mask" "F.Paste")
			(net "M_G_CPU1_SA_CS_N<0>")
		)
		(pad "65" smd rect
			(at -2.050034 -8.925052 270)
			(size 0.519938 1.4986)
			(layers "F.Cu" "F.Mask" "F.Paste")
			(net "GND")
		)
		(pad "66" smd rect
			(at -2.050034 -8.074914 270)
			(size 0.519938 1.4986)
			(layers "F.Cu" "F.Mask" "F.Paste")
			(net "M_G_CPU1_SA_CA<0>")
		)
		(pad "67" smd rect
			(at -2.050034 -7.22503 270)
			(size 0.519938 1.4986)
			(layers "F.Cu" "F.Mask" "F.Paste")
			(net "GND")
		)
		(pad "68" smd rect
			(at -2.050034 -6.374892 270)
			(size 0.519938 1.4986)
			(layers "F.Cu" "F.Mask" "F.Paste")
			(net "M_G_CPU1_SA_CA<2>")
		)
		(pad "69" smd rect
			(at -2.050034 -5.525008 270)
			(size 0.519938 1.4986)
			(layers "F.Cu" "F.Mask" "F.Paste")
			(net "GND")
		)
		(pad "70" smd rect
			(at -2.050034 -4.675124 270)
			(size 0.519938 1.4986)
			(layers "F.Cu" "F.Mask" "F.Paste")
			(net "M_G_CPU1_SA_CA<4>")
		)
		(pad "71" smd rect
			(at -2.050034 -3.824986 270)
			(size 0.519938 1.4986)
			(layers "F.Cu" "F.Mask" "F.Paste")
			(net "GND")
		)
		(pad "72" smd rect
			(at -2.050034 -2.975102 270)
			(size 0.519938 1.4986)
			(layers "F.Cu" "F.Mask" "F.Paste")
			(net "M_G_CPU1_SA_CA<6>")
		)
		(pad "73" smd rect
			(at -2.050034 -2.124964 270)
			(size 0.519938 1.4986)
			(layers "F.Cu" "F.Mask" "F.Paste")
			(net "GND")
		)
		(pad "74" smd rect
			(at -2.050034 -1.27508 270)
			(size 0.519938 1.4986)
			(layers "F.Cu" "F.Mask" "F.Paste")
			(net "M_G_CPU1_SA_PAR")
		)
		(pad "75" smd rect
			(at -2.050034 -0.424942 270)
			(size 0.519938 1.4986)
			(layers "F.Cu" "F.Mask" "F.Paste")
			(net "GND")
		)
		(pad "76" smd rect
			(at -2.050034 5.525008 270)
			(size 0.519938 1.4986)
			(layers "F.Cu" "F.Mask" "F.Paste")
			(net "M_G_CPU1_SB_CA<0>")
		)
		(pad "77" smd rect
			(at -2.050034 6.374892 270)
			(size 0.519938 1.4986)
			(layers "F.Cu" "F.Mask" "F.Paste")
			(net "GND")
		)
		(pad "78" smd rect
			(at -2.050034 7.22503 270)
			(size 0.519938 1.4986)
			(layers "F.Cu" "F.Mask" "F.Paste")
			(net "M_G_CPU1_SB_CA<2>")
		)
		(pad "79" smd rect
			(at -2.050034 8.074914 270)
			(size 0.519938 1.4986)
			(layers "F.Cu" "F.Mask" "F.Paste")
			(net "GND")
		)
		(pad "80" smd rect
			(at -2.050034 8.925052 270)
			(size 0.519938 1.4986)
			(layers "F.Cu" "F.Mask" "F.Paste")
			(net "M_G_CPU1_SB_CA<4>")
		)
		(pad "81" smd rect
			(at -2.050034 9.774936 270)
			(size 0.519938 1.4986)
			(layers "F.Cu" "F.Mask" "F.Paste")
			(net "GND")
		)
		(pad "82" smd rect
			(at -2.050034 10.625074 270)
			(size 0.519938 1.4986)
			(layers "F.Cu" "F.Mask" "F.Paste")
			(net "M_G_CPU1_SB_CA<6>")
		)
		(pad "83" smd rect
			(at -2.050034 11.474958 270)
			(size 0.519938 1.4986)
			(layers "F.Cu" "F.Mask" "F.Paste")
			(net "GND")
		)
		(pad "84" smd rect
			(at -2.050034 12.325096 270)
			(size 0.519938 1.4986)
			(layers "F.Cu" "F.Mask" "F.Paste")
			(net "M_G_CPU1_SB_CS_N<0>")
		)
		(pad "85" smd rect
			(at -2.050034 13.17498 270)
			(size 0.519938 1.4986)
			(layers "F.Cu" "F.Mask" "F.Paste")
			(net "GND")
		)
		(pad "86" smd rect
			(at -2.050034 14.025118 270)
			(size 0.519938 1.4986)
			(layers "F.Cu" "F.Mask" "F.Paste")
			(net "M_G_CPU1_SA_RSP<0>")
		)
		(pad "87" smd rect
			(at -2.050034 14.875002 270)
			(size 0.519938 1.4986)
			(layers "F.Cu" "F.Mask" "F.Paste")
			(net "M_G_CPU1_SB_RSP<0>")
		)
		(pad "88" smd rect
			(at -2.050034 15.724886 270)
			(size 0.519938 1.4986)
			(layers "F.Cu" "F.Mask" "F.Paste")
			(net "GND")
		)
		(pad "89" smd rect
			(at -2.050034 16.575024 270)
			(size 0.519938 1.4986)
			(layers "F.Cu" "F.Mask" "F.Paste")
			(net "M_G_CPU1_SB_CB<4>")
		)
		(pad "90" smd rect
			(at -2.050034 17.424908 270)
			(size 0.519938 1.4986)
			(layers "F.Cu" "F.Mask" "F.Paste")
			(net "GND")
		)
		(pad "91" smd rect
			(at -2.050034 18.275046 270)
			(size 0.519938 1.4986)
			(layers "F.Cu" "F.Mask" "F.Paste")
			(net "M_G_CPU1_SB_CB<5>")
		)
		(pad "92" smd rect
			(at -2.050034 19.12493 270)
			(size 0.519938 1.4986)
			(layers "F.Cu" "F.Mask" "F.Paste")
			(net "GND")
		)
		(pad "93" smd rect
			(at -2.050034 19.975068 270)
			(size 0.519938 1.4986)
			(layers "F.Cu" "F.Mask" "F.Paste")
			(net "M_G_CPU1_SB_DQS_DP<9>")
		)
		(pad "94" smd rect
			(at -2.050034 20.824952 270)
			(size 0.519938 1.4986)
			(layers "F.Cu" "F.Mask" "F.Paste")
			(net "M_G_CPU1_SB_DQS_DN<9>")
		)
		(pad "95" smd rect
			(at -2.050034 21.67509 270)
			(size 0.519938 1.4986)
			(layers "F.Cu" "F.Mask" "F.Paste")
			(net "GND")
		)
		(pad "96" smd rect
			(at -2.050034 22.524974 270)
			(size 0.519938 1.4986)
			(layers "F.Cu" "F.Mask" "F.Paste")
			(net "M_G_CPU1_SB_CB<0>")
		)
		(pad "97" smd rect
			(at -2.050034 23.375112 270)
			(size 0.519938 1.4986)
			(layers "F.Cu" "F.Mask" "F.Paste")
			(net "GND")
		)
		(pad "98" smd rect
			(at -2.050034 24.224996 270)
			(size 0.519938 1.4986)
			(layers "F.Cu" "F.Mask" "F.Paste")
			(net "M_G_CPU1_SB_CB<1>")
		)
		(pad "99" smd rect
			(at -2.050034 25.07488 270)
			(size 0.519938 1.4986)
			(layers "F.Cu" "F.Mask" "F.Paste")
			(net "GND")
		)
		(pad "100" smd rect
			(at -2.050034 25.925018 270)
			(size 0.519938 1.4986)
			(layers "F.Cu" "F.Mask" "F.Paste")
			(net "M_G_CPU1_SB_DQ<0>")
		)
		(pad "101" smd rect
			(at -2.050034 26.774902 270)
			(size 0.519938 1.4986)
			(layers "F.Cu" "F.Mask" "F.Paste")
			(net "GND")
		)
		(pad "102" smd rect
			(at -2.050034 27.62504 270)
			(size 0.519938 1.4986)
			(layers "F.Cu" "F.Mask" "F.Paste")
			(net "M_G_CPU1_SB_DQ<1>")
		)
		(pad "103" smd rect
			(at -2.050034 28.474924 270)
			(size 0.519938 1.4986)
			(layers "F.Cu" "F.Mask" "F.Paste")
			(net "GND")
		)
		(pad "104" smd rect
			(at -2.050034 29.325062 270)
			(size 0.519938 1.4986)
			(layers "F.Cu" "F.Mask" "F.Paste")
			(net "M_G_CPU1_SB_DQS_DP<0>")
		)
		(pad "105" smd rect
			(at -2.050034 30.174946 270)
			(size 0.519938 1.4986)
			(layers "F.Cu" "F.Mask" "F.Paste")
			(net "M_G_CPU1_SB_DQS_DN<0>")
		)
		(pad "106" smd rect
			(at -2.050034 31.025084 270)
			(size 0.519938 1.4986)
			(layers "F.Cu" "F.Mask" "F.Paste")
			(net "GND")
		)
		(pad "107" smd rect
			(at -2.050034 31.874968 270)
			(size 0.519938 1.4986)
			(layers "F.Cu" "F.Mask" "F.Paste")
			(net "M_G_CPU1_SB_DQ<4>")
		)
		(pad "108" smd rect
			(at -2.050034 32.725106 270)
			(size 0.519938 1.4986)
			(layers "F.Cu" "F.Mask" "F.Paste")
			(net "GND")
		)
		(pad "109" smd rect
			(at -2.050034 33.57499 270)
			(size 0.519938 1.4986)
			(layers "F.Cu" "F.Mask" "F.Paste")
			(net "M_G_CPU1_SB_DQ<5>")
		)
		(pad "110" smd rect
			(at -2.050034 34.425128 270)
			(size 0.519938 1.4986)
			(layers "F.Cu" "F.Mask" "F.Paste")
			(net "GND")
		)
		(pad "111" smd rect
			(at -2.050034 35.275012 270)
			(size 0.519938 1.4986)
			(layers "F.Cu" "F.Mask" "F.Paste")
			(net "M_G_CPU1_SB_DQ<8>")
		)
		(pad "112" smd rect
			(at -2.050034 36.124896 270)
			(size 0.519938 1.4986)
			(layers "F.Cu" "F.Mask" "F.Paste")
			(net "GND")
		)
	)
)
